(kicad_pcb
	(version 20241229)
	(generator "pcbnew")
	(generator_version "9.0")
	(general
		(thickness 1.552)
		(legacy_teardrops no)
	)
	(paper "A4")
	(title_block
		(date "2023-07-25")
		(rev "1.1.4")
		(comment 9 "footprints 159-163 of 379")
	)
	(layers
		(0 "F.Cu" signal)
		(4 "In1.Cu" signal)
		(6 "In2.Cu" signal)
		(8 "In3.Cu" signal)
		(10 "In4.Cu" signal)
		(12 "In5.Cu" signal)
		(14 "In6.Cu" signal)
		(2 "B.Cu" signal)
		(9 "F.Adhes" user "F.Adhesive")
		(11 "B.Adhes" user "B.Adhesive")
		(13 "F.Paste" user)
		(15 "B.Paste" user)
		(5 "F.SilkS" user "F.Silkscreen")
		(7 "B.SilkS" user "B.Silkscreen")
		(1 "F.Mask" user)
		(3 "B.Mask" user)
		(17 "Dwgs.User" user "User.Drawings")
		(19 "Cmts.User" user "User.Comments")
		(21 "Eco1.User" user "User.Eco1")
		(23 "Eco2.User" user "User.Eco2")
		(25 "Edge.Cuts" user)
		(27 "Margin" user)
		(31 "F.CrtYd" user "F.Courtyard")
		(29 "B.CrtYd" user "B.Courtyard")
		(35 "F.Fab" user)
		(33 "B.Fab" user)
	)
	(footprint "antmicro-footprints:MP_Pad5.4mm_Drill2.7mm"
		(layer "F.Cu")
		(at 170.03 120.15)
		(descr "Mounting Hole 2.7mm, M2.5")
		(tags "mounting hole 2.7mm m2.5")
		(property "Reference" "MP4"
			(at 0 -2.9 0)
			(layer "F.SilkS")
			(hide yes)
			(effects
				(font
					(size 0.7 0.7)
					(thickness 0.15)
				)
				(justify left bottom)
			)
		)
		(property "Value" "MP_Pad5.4mm_Drill2.7mm"
			(at 0 3.6 0)
			(layer "F.Fab")
			(effects
				(font
					(size 0.7 0.7)
					(thickness 0.15)
				)
				(justify left bottom)
			)
		)
		(property "Description" "Mechanical part"
			(at 0 0 0)
			(layer "F.Fab")
			(hide yes)
			(effects
				(font
					(size 1.27 1.27)
					(thickness 0.15)
				)
			)
		)
		(property "Author" "Antmicro"
			(at 0 0 0)
			(unlocked yes)
			(layer "F.Fab")
			(hide yes)
			(effects
				(font
					(size 1 1)
					(thickness 0.15)
				)
			)
		)
		(property "License" "Apache-2.0"
			(at 0 0 0)
			(unlocked yes)
			(layer "F.Fab")
			(hide yes)
			(effects
				(font
					(size 1 1)
					(thickness 0.15)
				)
			)
		)
		(sheetname "/")
		(sheetfile "sdi-mipi-video-converter.kicad_sch")
		(attr exclude_from_pos_files exclude_from_bom)
		(fp_circle
			(center 0 0)
			(end 2.95 0)
			(stroke
				(width 0.05)
				(type default)
			)
			(fill no)
			(layer "F.CrtYd")
		)
		(fp_text user "Author: Antmicro"
			(at -8.4 7.2 0)
			(layer "F.Fab")
			(effects
				(font
					(size 0.7 0.7)
					(thickness 0.15)
				)
				(justify left bottom)
			)
		)
		(fp_text user "${REFERENCE}"
			(at -8.4 6 0)
			(layer "F.Fab")
			(effects
				(font
					(size 0.7 0.7)
					(thickness 0.15)
				)
				(justify left bottom)
			)
		)
		(fp_text user "License: Apache-2.0"
			(at -8.4 8.4 0)
			(layer "F.Fab")
			(effects
				(font
					(size 0.7 0.7)
					(thickness 0.15)
				)
				(justify left bottom)
			)
		)
		(pad "1" thru_hole circle
			(at 0 0)
			(size 5.4 5.4)
			(drill 2.7)
			(layers "*.Cu" "*.Mask")
			(remove_unused_layers no)
			(net 401 "unconnected-(MP4-Pad1)")
			(pintype "passive+no_connect")
			(solder_paste_margin_ratio -1)
		)
	)
	(footprint "antmicro-footprints:R_0402_1005Metric"
		(layer "F.Cu")
		(at 166.09 69.85 90)
		(descr "Resistor SMD 0402")
		(tags "resistor SMD 0402")
		(property "Reference" "R14"
			(at 1.21 -0.36 180)
			(layer "F.SilkS")
			(effects
				(font
					(size 0.65 0.65)
					(thickness 0.15)
				)
				(justify left bottom)
			)
		)
		(property "Value" "R_470R_0402"
			(at 0 1.4 90)
			(layer "F.Fab")
			(hide yes)
			(effects
				(font
					(size 0.7 0.7)
					(thickness 0.15)
				)
				(justify left bottom)
			)
		)
		(property "Datasheet" "https://www.bourns.com/docs/product-datasheets/cr.pdf"
			(at 0 0 90)
			(layer "F.Fab")
			(hide yes)
			(effects
				(font
					(size 1.27 1.27)
					(thickness 0.15)
				)
			)
		)
		(property "Description" "SMD Chip Resistor, 470 ohm, ± 1%, 62.5 mW, 0402 [1005 Metric], Thick Film, General Purpose"
			(at 0 0 90)
			(layer "F.Fab")
			(hide yes)
			(effects
				(font
					(size 1.27 1.27)
					(thickness 0.15)
				)
			)
		)
		(property "Author" "Antmicro"
			(at 235.94 -96.24 0)
			(layer "F.Fab")
			(hide yes)
			(effects
				(font
					(size 1 1)
					(thickness 0.15)
				)
			)
		)
		(property "License" "Apache-2.0"
			(at 235.94 -96.24 0)
			(layer "F.Fab")
			(hide yes)
			(effects
				(font
					(size 1 1)
					(thickness 0.15)
				)
			)
		)
		(property "MPN" "CR0402-FX-4700GLF"
			(at 235.94 -96.24 0)
			(layer "F.Fab")
			(hide yes)
			(effects
				(font
					(size 1 1)
					(thickness 0.15)
				)
			)
		)
		(property "Manufacturer" "Bourns"
			(at 235.94 -96.24 0)
			(layer "F.Fab")
			(hide yes)
			(effects
				(font
					(size 1 1)
					(thickness 0.15)
				)
			)
		)
		(property "Tolerance" "1%"
			(at 235.94 -96.24 0)
			(layer "F.Fab")
			(hide yes)
			(effects
				(font
					(size 1 1)
					(thickness 0.15)
				)
			)
		)
		(property "Val" "470R"
			(at 235.94 -96.24 0)
			(layer "F.Fab")
			(hide yes)
			(effects
				(font
					(size 1 1)
					(thickness 0.15)
				)
			)
		)
		(sheetname "/Power Supply/")
		(sheetfile "supply.kicad_sch")
		(attr smd)
		(fp_rect
			(start -0.925 -0.47)
			(end 0.925 0.47)
			(stroke
				(width 0.05)
				(type default)
			)
			(fill no)
			(layer "F.CrtYd")
		)
		(fp_rect
			(start -0.5 -0.25)
			(end 0.5 0.25)
			(stroke
				(width 0.15)
				(type solid)
			)
			(fill no)
			(layer "F.Fab")
		)
		(fp_text user "${REFERENCE}"
			(at -0.95 3.168 90)
			(layer "F.Fab")
			(effects
				(font
					(size 0.7 0.7)
					(thickness 0.15)
				)
				(justify left bottom)
			)
		)
		(fp_text user "Author: Antmicro"
			(at -0.95 4.169 90)
			(layer "F.Fab")
			(effects
				(font
					(size 0.7 0.7)
					(thickness 0.15)
				)
				(justify left bottom)
			)
		)
		(fp_text user "License: Apache-2.0"
			(at -0.95 5.169 90)
			(layer "F.Fab")
			(effects
				(font
					(size 0.7 0.7)
					(thickness 0.15)
				)
				(justify left bottom)
			)
		)
		(pad "1" smd roundrect
			(at -0.48 0 90)
			(size 0.59 0.64)
			(layers "F.Cu" "F.Mask" "F.Paste")
			(roundrect_rratio 0.25)
			(net 58 "Net-(D1-A)")
			(pintype "passive")
		)
		(pad "2" smd roundrect
			(at 0.48 0 90)
			(size 0.59 0.64)
			(layers "F.Cu" "F.Mask" "F.Paste")
			(roundrect_rratio 0.25)
			(net 14 "+5V")
			(pintype "passive")
		)
	)
	(footprint "antmicro-footprints:R_0402_1005Metric"
		(layer "F.Cu")
		(at 133.83 111.15 180)
		(descr "Resistor SMD 0402")
		(tags "resistor SMD 0402")
		(property "Reference" "R70"
			(at 3.2 0.01 180)
			(layer "F.SilkS")
			(effects
				(font
					(size 0.65 0.65)
					(thickness 0.15)
				)
				(justify left bottom)
			)
		)
		(property "Value" "R_100R_0402"
			(at 0 1.4 180)
			(layer "F.Fab")
			(hide yes)
			(effects
				(font
					(size 0.7 0.7)
					(thickness 0.15)
				)
				(justify left bottom)
			)
		)
		(property "Datasheet" "https://www.bourns.com/docs/product-datasheets/cr.pdf"
			(at 0 0 180)
			(layer "F.Fab")
			(hide yes)
			(effects
				(font
					(size 1.27 1.27)
					(thickness 0.15)
				)
			)
		)
		(property "Description" "SMD Chip Resistor, 100 ohm, ± 1%, 62.5 mW, 0402 [1005 Metric], Thick Film, General Purpose"
			(at 0 0 180)
			(layer "F.Fab")
			(hide yes)
			(effects
				(font
					(size 1.27 1.27)
					(thickness 0.15)
				)
			)
		)
		(property "Author" "Antmicro"
			(at 267.66 222.3 0)
			(layer "F.Fab")
			(hide yes)
			(effects
				(font
					(size 1 1)
					(thickness 0.15)
				)
			)
		)
		(property "License" "Apache-2.0"
			(at 267.66 222.3 0)
			(layer "F.Fab")
			(hide yes)
			(effects
				(font
					(size 1 1)
					(thickness 0.15)
				)
			)
		)
		(property "MPN" "CR0402-FX-1000GLF"
			(at 267.66 222.3 0)
			(layer "F.Fab")
			(hide yes)
			(effects
				(font
					(size 1 1)
					(thickness 0.15)
				)
			)
		)
		(property "Manufacturer" "Bourns"
			(at 267.66 222.3 0)
			(layer "F.Fab")
			(hide yes)
			(effects
				(font
					(size 1 1)
					(thickness 0.15)
				)
			)
		)
		(property "Tolerance" "1%"
			(at 267.66 222.3 0)
			(layer "F.Fab")
			(hide yes)
			(effects
				(font
					(size 1 1)
					(thickness 0.15)
				)
			)
		)
		(property "Val" "100R"
			(at 267.66 222.3 0)
			(layer "F.Fab")
			(hide yes)
			(effects
				(font
					(size 1 1)
					(thickness 0.15)
				)
			)
		)
		(sheetname "/FPGA/")
		(sheetfile "fpga.kicad_sch")
		(attr smd)
		(fp_rect
			(start -0.925 -0.47)
			(end 0.925 0.47)
			(stroke
				(width 0.05)
				(type default)
			)
			(fill no)
			(layer "F.CrtYd")
		)
		(fp_rect
			(start -0.5 -0.25)
			(end 0.5 0.25)
			(stroke
				(width 0.15)
				(type solid)
			)
			(fill no)
			(layer "F.Fab")
		)
		(fp_text user "${REFERENCE}"
			(at -0.95 3.168 180)
			(layer "F.Fab")
			(effects
				(font
					(size 0.7 0.7)
					(thickness 0.15)
				)
				(justify left bottom)
			)
		)
		(fp_text user "License: Apache-2.0"
			(at -0.95 5.169 180)
			(layer "F.Fab")
			(effects
				(font
					(size 0.7 0.7)
					(thickness 0.15)
				)
				(justify left bottom)
			)
		)
		(fp_text user "Author: Antmicro"
			(at -0.95 4.169 180)
			(layer "F.Fab")
			(effects
				(font
					(size 0.7 0.7)
					(thickness 0.15)
				)
				(justify left bottom)
			)
		)
		(pad "1" smd roundrect
			(at -0.48 0 180)
			(size 0.59 0.64)
			(layers "F.Cu" "F.Mask" "F.Paste")
			(roundrect_rratio 0.25)
			(net 36 "/FPGA/PROGRAMN")
			(pintype "passive")
		)
		(pad "2" smd roundrect
			(at 0.48 0 180)
			(size 0.59 0.64)
			(layers "F.Cu" "F.Mask" "F.Paste")
			(roundrect_rratio 0.25)
			(net 381 "Net-(C80-Pad2)")
			(pintype "passive")
		)
	)
	(footprint "antmicro-footprints:R_0402_1005Metric"
		(layer "F.Cu")
		(at 122.03 112.15 180)
		(descr "Resistor SMD 0402")
		(tags "resistor SMD 0402")
		(property "Reference" "R89"
			(at 1 -0.39 0)
			(layer "F.SilkS")
			(effects
				(font
					(size 0.65 0.65)
					(thickness 0.15)
				)
				(justify right bottom)
			)
		)
		(property "Value" "R_2k2_0402"
			(at 0 1.4 0)
			(layer "F.Fab")
			(hide yes)
			(effects
				(font
					(size 0.7 0.7)
					(thickness 0.15)
				)
				(justify right bottom)
			)
		)
		(property "Datasheet" "https://www.bourns.com/docs/product-datasheets/cr.pdf"
			(at 0 0 180)
			(layer "F.Fab")
			(hide yes)
			(effects
				(font
					(size 1.27 1.27)
					(thickness 0.15)
				)
			)
		)
		(property "Description" "SMD Chip Resistor, 2.2 kohm, ± 1%, 62.5 mW, 0402 [1005 Metric], Thick Film, General Purpose"
			(at 0 0 180)
			(layer "F.Fab")
			(hide yes)
			(effects
				(font
					(size 1.27 1.27)
					(thickness 0.15)
				)
			)
		)
		(property "Author" "Antmicro"
			(at 244.06 224.3 0)
			(layer "F.Fab")
			(hide yes)
			(effects
				(font
					(size 1 1)
					(thickness 0.15)
				)
			)
		)
		(property "License" "Apache-2.0"
			(at 244.06 224.3 0)
			(layer "F.Fab")
			(hide yes)
			(effects
				(font
					(size 1 1)
					(thickness 0.15)
				)
			)
		)
		(property "MPN" "CR0402-FX-2201GLF"
			(at 244.06 224.3 0)
			(layer "F.Fab")
			(hide yes)
			(effects
				(font
					(size 1 1)
					(thickness 0.15)
				)
			)
		)
		(property "Manufacturer" "Bourns"
			(at 244.06 224.3 0)
			(layer "F.Fab")
			(hide yes)
			(effects
				(font
					(size 1 1)
					(thickness 0.15)
				)
			)
		)
		(property "Tolerance" "1%"
			(at 244.06 224.3 0)
			(layer "F.Fab")
			(hide yes)
			(effects
				(font
					(size 1 1)
					(thickness 0.15)
				)
			)
		)
		(property "Val" "2k2"
			(at 244.06 224.3 0)
			(layer "F.Fab")
			(hide yes)
			(effects
				(font
					(size 1 1)
					(thickness 0.15)
				)
			)
		)
		(sheetname "/FPGA/")
		(sheetfile "fpga.kicad_sch")
		(attr smd)
		(fp_rect
			(start -0.925 -0.47)
			(end 0.925 0.47)
			(stroke
				(width 0.05)
				(type default)
			)
			(fill no)
			(layer "F.CrtYd")
		)
		(fp_rect
			(start -0.5 -0.25)
			(end 0.5 0.25)
			(stroke
				(width 0.15)
				(type solid)
			)
			(fill no)
			(layer "F.Fab")
		)
		(fp_text user "${REFERENCE}"
			(at -0.95 3.168 180)
			(layer "F.Fab")
			(effects
				(font
					(size 0.7 0.7)
					(thickness 0.15)
				)
				(justify left bottom)
			)
		)
		(fp_text user "License: Apache-2.0"
			(at -0.95 5.169 180)
			(layer "F.Fab")
			(effects
				(font
					(size 0.7 0.7)
					(thickness 0.15)
				)
				(justify left bottom)
			)
		)
		(fp_text user "Author: Antmicro"
			(at -0.95 4.169 180)
			(layer "F.Fab")
			(effects
				(font
					(size 0.7 0.7)
					(thickness 0.15)
				)
				(justify left bottom)
			)
		)
		(pad "1" smd roundrect
			(at -0.48 0 180)
			(size 0.59 0.64)
			(layers "F.Cu" "F.Mask" "F.Paste")
			(roundrect_rratio 0.25)
			(net 67 "Net-(D5-A)")
			(pintype "passive")
		)
		(pad "2" smd roundrect
			(at 0.48 0 180)
			(size 0.59 0.64)
			(layers "F.Cu" "F.Mask" "F.Paste")
			(roundrect_rratio 0.25)
			(net 2 "+3V3")
			(pintype "passive")
		)
	)
	(footprint "antmicro-footprints:R_0402_1005Metric"
		(layer "F.Cu")
		(at 90.8 69.2 -90)
		(descr "Resistor SMD 0402")
		(tags "resistor SMD 0402")
		(property "Reference" "R55"
			(at -1.31 -0.48 90)
			(layer "F.SilkS")
			(effects
				(font
					(size 0.65 0.65)
					(thickness 0.15)
				)
				(justify left bottom)
			)
		)
		(property "Value" "R_100k_0402"
			(at 0 1.4 90)
			(layer "F.Fab")
			(hide yes)
			(effects
				(font
					(size 0.7 0.7)
					(thickness 0.15)
				)
				(justify right bottom)
			)
		)
		(property "Datasheet" "https://www.bourns.com/docs/product-datasheets/cr.pdf"
			(at 0 0 270)
			(layer "F.Fab")
			(hide yes)
			(effects
				(font
					(size 1.27 1.27)
					(thickness 0.15)
				)
			)
		)
		(property "Description" "SMD Chip Resistor, 100 kohm, ± 1%, 62.5 mW, 0402 [1005 Metric], Thick Film, General Purpose"
			(at 0 0 270)
			(layer "F.Fab")
			(hide yes)
			(effects
				(font
					(size 1.27 1.27)
					(thickness 0.15)
				)
			)
		)
		(property "Author" "Antmicro"
			(at 21.6 160 0)
			(layer "F.Fab")
			(hide yes)
			(effects
				(font
					(size 1 1)
					(thickness 0.15)
				)
			)
		)
		(property "License" "Apache-2.0"
			(at 21.6 160 0)
			(layer "F.Fab")
			(hide yes)
			(effects
				(font
					(size 1 1)
					(thickness 0.15)
				)
			)
		)
		(property "MPN" "CR0402-FX-1003GLF"
			(at 21.6 160 0)
			(layer "F.Fab")
			(hide yes)
			(effects
				(font
					(size 1 1)
					(thickness 0.15)
				)
			)
		)
		(property "Manufacturer" "Bourns"
			(at 21.6 160 0)
			(layer "F.Fab")
			(hide yes)
			(effects
				(font
					(size 1 1)
					(thickness 0.15)
				)
			)
		)
		(property "Tolerance" "1%"
			(at 21.6 160 0)
			(layer "F.Fab")
			(hide yes)
			(effects
				(font
					(size 1 1)
					(thickness 0.15)
				)
			)
		)
		(property "Val" "100k"
			(at 21.6 160 0)
			(layer "F.Fab")
			(hide yes)
			(effects
				(font
					(size 1 1)
					(thickness 0.15)
				)
			)
		)
		(sheetname "/SDI/")
		(sheetfile "sdi.kicad_sch")
		(attr smd)
		(fp_rect
			(start -0.925 -0.47)
			(end 0.925 0.47)
			(stroke
				(width 0.05)
				(type default)
			)
			(fill no)
			(layer "F.CrtYd")
		)
		(fp_rect
			(start -0.5 -0.25)
			(end 0.5 0.25)
			(stroke
				(width 0.15)
				(type solid)
			)
			(fill no)
			(layer "F.Fab")
		)
		(fp_text user "Author: Antmicro"
			(at -0.95 4.169 270)
			(layer "F.Fab")
			(effects
				(font
					(size 0.7 0.7)
					(thickness 0.15)
				)
				(justify left bottom)
			)
		)
		(fp_text user "${REFERENCE}"
			(at -0.95 3.168 270)
			(layer "F.Fab")
			(effects
				(font
					(size 0.7 0.7)
					(thickness 0.15)
				)
				(justify left bottom)
			)
		)
		(fp_text user "License: Apache-2.0"
			(at -0.95 5.169 270)
			(layer "F.Fab")
			(effects
				(font
					(size 0.7 0.7)
					(thickness 0.15)
				)
				(justify left bottom)
			)
		)
		(pad "1" smd roundrect
			(at -0.48 0 270)
			(size 0.59 0.64)
			(layers "F.Cu" "F.Mask" "F.Paste")
			(roundrect_rratio 0.25)
			(net 2 "+3V3")
			(pintype "passive")
		)
		(pad "2" smd roundrect
			(at 0.48 0 270)
			(size 0.59 0.64)
			(layers "F.Cu" "F.Mask" "F.Paste")
			(roundrect_rratio 0.25)
			(net 288 "Net-(U15B-LB_CONT)")
			(pintype "passive")
		)
	)
)
